FILE_TYPE = MACRO_DRAWING;
SET COLOR_WIRE YELLOW;
SET COLOR_PROP ORANGE;
SET COLOR_DOT WHITE;
SET COLOR_ARC YELLOW;
SET COLOR_BODY GREEN;
SET COLOR_NOTE PURPLE;
SET PROP_DISPLAY VALUE;
SET PAGE_NUMBER P56;
FORCEADD OFFPAGE..1
(-7625 4250);
FORCEPROP 2 LAST $XR0 75 
J 0
(-7846 4250);
DISPLAY 0.638298 (-7846 4250);
PAINT MONO (-7846 4250);
FORCEPROP 2 LAST PATH I10
J 0
(-7875 4300);
DISPLAY 1.021277 (-7875 4300);
DISPLAY INVISIBLE (-7875 4300);
FORCEPROP 1 LAST COMMENT_BODY TRUE
J 0
(-7500 4150);
DISPLAY 0.872340 (-7500 4150);
PAINT GREEN (-7500 4150);
DISPLAY INVISIBLE (-7500 4150);
FORCEPROP 1 LAST OFFPAGE TRUE
J 0
(-7300 4125);
DISPLAY 0.872340 (-7300 4125);
PAINT GREEN (-7300 4125);
DISPLAY INVISIBLE (-7300 4125);
FORCEPROP 2 LAST CDS_LIB standard
J 0
(-7625 4250);
DISPLAY INVISIBLE (-7625 4250);
FORCEADD Q_RES..1
(-6800 5500);
FORCEPROP 1 LAST LOCATION R738
J 0
(-6675 5500);
DISPLAY 0.489362 (-6675 5500);
PAINT SKYBLUE (-6675 5500);
FORCEPROP 0 LAST $SEC 1
J 0
(-6675 5525);
DISPLAY 0.680851 (-6675 5525);
PAINT MONO (-6675 5525);
DISPLAY INVISIBLE (-6675 5525);
FORCEPROP 0 LAST CDS_SEC 1
J 0
(-6675 5525);
DISPLAY 0.680851 (-6675 5525);
DISPLAY INVISIBLE (-6675 5525);
FORCEPROP 1 LASTPIN (-6900 5500) $PN 1
J 0
(-6888 5512);
DISPLAY 0.489362 (-6888 5512);
PAINT MONO (-6888 5512);
FORCEPROP 1 LASTPIN (-6700 5500) $PN 2
J 0
(-6738 5512);
DISPLAY 0.489362 (-6738 5512);
PAINT MONO (-6738 5512);
FORCEPROP 1 LAST VALUE 33
J 2
(-6900 5500);
DISPLAY 0.489362 (-6900 5500);
PAINT SKYBLUE (-6900 5500);
FORCEPROP 2 LAST CDS_LIB pure_quanta
J 0
(-6800 5500);
DISPLAY INVISIBLE (-6800 5500);
FORCEPROP 1 LAST PATH I11
J 0
(-6850 5650);
DISPLAY 0.978723 (-6850 5650);
PAINT WHITE (-6850 5650);
DISPLAY INVISIBLE (-6850 5650);
FORCEPROP 1 LAST WATTAGE 1/16W
J 2
(-6400 5425);
DISPLAY 0.489362 (-6400 5425);
PAINT SKYBLUE (-6400 5425);
DISPLAY INVISIBLE (-6400 5425);
FORCEPROP 1 LAST MATERIAL CHIP
J 0
(-6375 5425);
DISPLAY 0.489362 (-6375 5425);
PAINT SKYBLUE (-6375 5425);
DISPLAY INVISIBLE (-6375 5425);
FORCEPROP 1 LAST TOLERANCE 5%
J 0
(-6825 5425);
DISPLAY 0.489362 (-6825 5425);
PAINT SKYBLUE (-6825 5425);
DISPLAY INVISIBLE (-6825 5425);
FORCEPROP 1 LAST PART_NUMBER CS03302JB29
J 0
(-6775 5550);
DISPLAY 0.489362 (-6775 5550);
PAINT SKYBLUE (-6775 5550);
DISPLAY INVISIBLE (-6775 5550);
FORCEPROP 1 LAST PACK_TYPE 0402LF
J 0
(-6750 5425);
DISPLAY 0.489362 (-6750 5425);
PAINT SKYBLUE (-6750 5425);
DISPLAY INVISIBLE (-6750 5425);
FORCEADD OFFPAGE..2
R 2
(-7625 5500);
FORCEPROP 2 LAST $XR0 75 
J 0
(-7879 5500);
DISPLAY 0.638298 (-7879 5500);
PAINT MONO (-7879 5500);
FORCEPROP 2 LAST PATH I12
J 0
(-7875 5550);
DISPLAY 0.680851 (-7875 5550);
DISPLAY INVISIBLE (-7875 5550);
FORCEPROP 1 LAST COMMENT_BODY TRUE
J 2
(-7580 5405);
DISPLAY 0.872340 (-7580 5405);
PAINT PEACH (-7580 5405);
DISPLAY INVISIBLE (-7580 5405);
FORCEPROP 1 LAST OFFPAGE TRUE
J 2
(-7950 5375);
DISPLAY 0.872340 (-7950 5375);
PAINT GREEN (-7950 5375);
DISPLAY INVISIBLE (-7950 5375);
FORCEPROP 2 LAST CDS_LIB standard
J 2
(-7625 5500);
DISPLAY INVISIBLE (-7625 5500);
FORCEADD GENOA_SP5..22
(-4525 4675);
FORCEPROP 1 LAST LOCATION U26
J 0
(-5620 6206);
DISPLAY 0.489362 (-5620 6206);
PAINT SKYBLUE (-5620 6206);
FORCEPROP 0 LAST $SEC 22
J 0
(-5600 6250);
DISPLAY 0.680851 (-5600 6250);
PAINT MONO (-5600 6250);
DISPLAY INVISIBLE (-5600 6250);
FORCEPROP 0 LAST CDS_SEC 22
J 0
(-5625 6225);
DISPLAY 1.021277 (-5625 6225);
DISPLAY INVISIBLE (-5625 6225);
FORCEPROP 0 LASTPIN (-5775 4100) $PN DJ25
J 2
(-5785 4110);
DISPLAY 0.489362 (-5785 4110);
PAINT MONO (-5785 4110);
FORCEPROP 0 LASTPIN (-5775 4350) $PN DJ22
J 2
(-5785 4360);
DISPLAY 0.489362 (-5785 4360);
PAINT MONO (-5785 4360);
FORCEPROP 0 LASTPIN (-5775 5100) $PN DF28
J 2
(-5785 5110);
DISPLAY 0.489362 (-5785 5110);
PAINT MONO (-5785 5110);
FORCEPROP 0 LASTPIN (-5775 5050) $PN DG22
J 2
(-5785 5060);
DISPLAY 0.489362 (-5785 5060);
PAINT MONO (-5785 5060);
FORCEPROP 0 LASTPIN (-5775 5000) $PN DJ28
J 2
(-5785 5010);
DISPLAY 0.489362 (-5785 5010);
PAINT MONO (-5785 5010);
FORCEPROP 0 LASTPIN (-5775 4950) $PN DG29
J 2
(-5785 4960);
DISPLAY 0.489362 (-5785 4960);
PAINT MONO (-5785 4960);
FORCEPROP 0 LASTPIN (-5775 4500) $PN DF24
J 2
(-5785 4510);
DISPLAY 0.489362 (-5785 4510);
PAINT MONO (-5785 4510);
FORCEPROP 0 LASTPIN (-5775 4800) $PN DH24
J 2
(-5785 4810);
DISPLAY 0.489362 (-5785 4810);
PAINT MONO (-5785 4810);
FORCEPROP 0 LASTPIN (-5775 4750) $PN DE24
J 2
(-5785 4760);
DISPLAY 0.489362 (-5785 4760);
PAINT MONO (-5785 4760);
FORCEPROP 0 LASTPIN (-5775 4700) $PN DF25
J 2
(-5785 4710);
DISPLAY 0.489362 (-5785 4710);
PAINT MONO (-5785 4710);
FORCEPROP 0 LASTPIN (-5775 4650) $PN DG25
J 2
(-5785 4660);
DISPLAY 0.489362 (-5785 4660);
PAINT MONO (-5785 4660);
FORCEPROP 0 LASTPIN (-5775 5500) $PN DJ27
J 2
(-5785 5510);
DISPLAY 0.489362 (-5785 5510);
PAINT MONO (-5785 5510);
FORCEPROP 0 LASTPIN (-5775 4300) $PN DG23
J 2
(-5785 4310);
DISPLAY 0.489362 (-5785 4310);
PAINT MONO (-5785 4310);
FORCEPROP 0 LASTPIN (-5775 4250) $PN DF27
J 2
(-5785 4260);
DISPLAY 0.489362 (-5785 4260);
PAINT MONO (-5785 4260);
FORCEPROP 0 LASTPIN (-5775 5450) $PN DG28
J 2
(-5785 5460);
DISPLAY 0.489362 (-5785 5460);
PAINT MONO (-5785 5460);
FORCEPROP 0 LASTPIN (-5775 5400) $PN DJ23
J 2
(-5785 5410);
DISPLAY 0.489362 (-5785 5410);
PAINT MONO (-5785 5410);
FORCEPROP 0 LASTPIN (-5775 5300) $PN DJ26
J 2
(-5785 5310);
DISPLAY 0.489362 (-5785 5310);
PAINT MONO (-5785 5310);
FORCEPROP 0 LASTPIN (-5775 4200) $PN DE27
J 2
(-5785 4210);
DISPLAY 0.489362 (-5785 4210);
PAINT MONO (-5785 4210);
FORCEPROP 0 LASTPIN (-5775 5750) $PN DF30
J 2
(-5785 5760);
DISPLAY 0.489362 (-5785 5760);
PAINT MONO (-5785 5760);
FORCEPROP 0 LASTPIN (-5775 5700) $PN DG26
J 2
(-5785 5710);
DISPLAY 0.489362 (-5785 5710);
PAINT MONO (-5785 5710);
FORCEPROP 0 LASTPIN (-5775 5650) $PN DH27
J 2
(-5785 5660);
DISPLAY 0.489362 (-5785 5660);
PAINT MONO (-5785 5660);
FORCEPROP 0 LASTPIN (-3275 5700) $PN A25
J 0
(-3265 5710);
DISPLAY 0.489362 (-3265 5710);
PAINT MONO (-3265 5710);
FORCEPROP 0 LASTPIN (-3275 5750) $PN A26
J 0
(-3265 5760);
DISPLAY 0.489362 (-3265 5760);
PAINT MONO (-3265 5760);
FORCEPROP 0 LASTPIN (-3275 3800) $PN E23
J 0
(-3265 3810);
DISPLAY 0.489362 (-3265 3810);
PAINT MONO (-3265 3810);
FORCEPROP 0 LASTPIN (-3275 5050) $PN E26
J 0
(-3265 5060);
DISPLAY 0.489362 (-3265 5060);
PAINT MONO (-3265 5060);
FORCEPROP 0 LASTPIN (-3275 5100) $PN E27
J 0
(-3265 5110);
DISPLAY 0.489362 (-3265 5110);
PAINT MONO (-3265 5110);
FORCEPROP 0 LASTPIN (-3275 4400) $PN C26
J 0
(-3265 4410);
DISPLAY 0.489362 (-3265 4410);
PAINT MONO (-3265 4410);
FORCEPROP 0 LASTPIN (-3275 4450) $PN C25
J 0
(-3265 4460);
DISPLAY 0.489362 (-3265 4460);
PAINT MONO (-3265 4460);
FORCEPROP 0 LASTPIN (-3275 5550) $PN A29
J 0
(-3265 5560);
DISPLAY 0.489362 (-3265 5560);
PAINT MONO (-3265 5560);
FORCEPROP 0 LASTPIN (-3275 5600) $PN A28
J 0
(-3265 5610);
DISPLAY 0.489362 (-3265 5610);
PAINT MONO (-3265 5610);
FORCEPROP 0 LASTPIN (-3275 3750) $PN E24
J 0
(-3265 3760);
DISPLAY 0.489362 (-3265 3760);
PAINT MONO (-3265 3760);
FORCEPROP 0 LASTPIN (-3275 4900) $PN C28
J 0
(-3265 4910);
DISPLAY 0.489362 (-3265 4910);
PAINT MONO (-3265 4910);
FORCEPROP 0 LASTPIN (-3275 4950) $PN C29
J 0
(-3265 4960);
DISPLAY 0.489362 (-3265 4960);
PAINT MONO (-3265 4960);
FORCEPROP 0 LASTPIN (-3275 4250) $PN E29
J 0
(-3265 4260);
DISPLAY 0.489362 (-3265 4260);
PAINT MONO (-3265 4260);
FORCEPROP 0 LASTPIN (-3275 4300) $PN E30
J 0
(-3265 4310);
DISPLAY 0.489362 (-3265 4310);
PAINT MONO (-3265 4310);
FORCEPROP 0 LASTPIN (-3275 5400) $PN DH67
J 0
(-3265 5410);
DISPLAY 0.489362 (-3265 5410);
PAINT MONO (-3265 5410);
FORCEPROP 0 LASTPIN (-3275 5450) $PN DJ67
J 0
(-3265 5460);
DISPLAY 0.489362 (-3265 5460);
PAINT MONO (-3265 5460);
FORCEPROP 0 LASTPIN (-3275 3700) $PN DG40
J 0
(-3265 3710);
DISPLAY 0.489362 (-3265 3710);
PAINT MONO (-3265 3710);
FORCEPROP 0 LASTPIN (-3275 4750) $PN DH65
J 0
(-3265 4760);
DISPLAY 0.489362 (-3265 4760);
PAINT MONO (-3265 4760);
FORCEPROP 0 LASTPIN (-3275 4800) $PN DJ65
J 0
(-3265 4810);
DISPLAY 0.489362 (-3265 4810);
PAINT MONO (-3265 4810);
FORCEPROP 0 LASTPIN (-3275 4100) $PN DJ69
J 0
(-3265 4110);
DISPLAY 0.489362 (-3265 4110);
PAINT MONO (-3265 4110);
FORCEPROP 0 LASTPIN (-3275 4150) $PN DH69
J 0
(-3265 4160);
DISPLAY 0.489362 (-3265 4160);
PAINT MONO (-3265 4160);
FORCEPROP 0 LASTPIN (-3275 5250) $PN DJ60
J 0
(-3265 5260);
DISPLAY 0.489362 (-3265 5260);
PAINT MONO (-3265 5260);
FORCEPROP 0 LASTPIN (-3275 5300) $PN DH60
J 0
(-3265 5310);
DISPLAY 0.489362 (-3265 5310);
PAINT MONO (-3265 5310);
FORCEPROP 0 LASTPIN (-3275 3650) $PN DH40
J 0
(-3265 3660);
DISPLAY 0.489362 (-3265 3660);
PAINT MONO (-3265 3660);
FORCEPROP 0 LASTPIN (-3275 4600) $PN DH62
J 0
(-3265 4610);
DISPLAY 0.489362 (-3265 4610);
PAINT MONO (-3265 4610);
FORCEPROP 0 LASTPIN (-3275 4650) $PN DJ62
J 0
(-3265 4660);
DISPLAY 0.489362 (-3265 4660);
PAINT MONO (-3265 4660);
FORCEPROP 0 LASTPIN (-3275 3950) $PN DH58
J 0
(-3265 3960);
DISPLAY 0.489362 (-3265 3960);
PAINT MONO (-3265 3960);
FORCEPROP 0 LASTPIN (-3275 4000) $PN DG58
J 0
(-3265 4010);
DISPLAY 0.489362 (-3265 4010);
PAINT MONO (-3265 4010);
FORCEPROP 2 LAST PART_TYPE SMLF
J 0
(-5625 6175);
DISPLAY 1.021277 (-5625 6175);
FORCEPROP 1 LAST MATERIAL IO
J 0
(-5620 5932);
DISPLAY 0.489362 (-5620 5932);
PAINT SKYBLUE (-5620 5932);
FORCEPROP 2 LAST VALUE SOCKET6096_13568-001
J 0
(-5625 6075);
DISPLAY 0.489362 (-5625 6075);
PAINT SKYBLUE (-5625 6075);
FORCEPROP 1 LAST PART_NUMBER DGA^6000030
J 0
(-5620 6059);
DISPLAY 0.489362 (-5620 6059);
PAINT SKYBLUE (-5620 6059);
FORCEPROP 1 LAST NEEDS_NO_SIZE TRUE
J 0
(-4525 4675);
DISPLAY 0.723404 (-4525 4675);
PAINT GREEN (-4525 4675);
DISPLAY INVISIBLE (-4525 4675);
FORCEPROP 1 LAST CDS_LMAN_SYM_OUTLINE -1100,1225,1100,-1225
J 0
(-4525 4675);
DISPLAY 0.468085 (-4525 4675);
PAINT GREEN (-4525 4675);
DISPLAY INVISIBLE (-4525 4675);
FORCEPROP 2 LAST CDS_LIB pure_quanta
J 0
(-4525 4675);
DISPLAY INVISIBLE (-4525 4675);
FORCEPROP 1 LAST PATH I8
J 0
(-4525 4675);
DISPLAY 0.723404 (-4525 4675);
PAINT GREEN (-4525 4675);
DISPLAY INVISIBLE (-4525 4675);
FORCEADD QUANTA_TITLE_BLOCK_C..1
(0 0);
FORCEPROP 0 LAST CDS_CON_LAST_MODIFIED Fri Mar 11 14:52:39 2022
J 0
(-1885 15);
DISPLAY INVISIBLE (-1885 15);
FORCEPROP 1 LAST CUSTOM_TXT_CDS <CON_LAST_MODIFIED>
J 0
(-1885 15);
DISPLAY 0.978723 (-1885 15);
FORCEPROP 2 LAST CUSTOM_TXT_CDS <XR_PAGE_TITLE>
J 0
(-7890 5250);
DISPLAY 0.638298 (-7890 5250);
PAINT PINK (-7890 5250);
DISPLAY INVISIBLE (-7890 5250);
FORCEPROP 1 LAST CUSTOM_TXT_CDS <NAME_2>
J 0
(-3175 50);
FORCEPROP 1 LAST CUSTOM_TXT_CDS <NAME_1>
J 0
(-3175 175);
FORCEPROP 1 LAST CUSTOM_TXT_CDS <Q_NUMBER>
J 0
(-1403 103);
DISPLAY 1.212766 (-1403 103);
FORCEPROP 1 LAST CUSTOM_TXT_CDS <Q_PROJ>
J 0
(-2382 102);
DISPLAY 1.212766 (-2382 102);
FORCEPROP 1 LAST CUSTOM_TXT_CDS <Q_REV>
J 0
(-184 103);
DISPLAY 1.212766 (-184 103);
FORCEPROP 1 LAST CUSTOM_TXT_CDS <CON_PAGE_NUM> OF <CON_TOTAL_PAGES>
J 0
(-446 18);
DISPLAY 0.978723 (-446 18);
FORCEPROP 1 LAST Q_DEPT BU9
J 1
(-3763 49);
DISPLAY 1.957447 (-3763 49);
PAINT GREEN (-3763 49);
FORCEPROP 1 LAST Q_TITLE CPU1 SPI/USB
J 0
(-9300 50);
DISPLAY 2.446809 (-9300 50);
PAINT GREEN (-9300 50);
FORCEPROP 2 LAST CDS_LIB pure_quanta
J 0
(0 0);
DISPLAY INVISIBLE (0 0);
FORCEPROP 1 LAST CDS_LMAN_SYM_OUTLINE -9475,6775,100,-125
J 0
(0 0);
DISPLAY 0.468085 (0 0);
PAINT GREEN (0 0);
DISPLAY INVISIBLE (0 0);
FORCEPROP 2 LAST PAGE_BORDER TRUE
J 0
(-7890 5250);
DISPLAY 0.638298 (-7890 5250);
PAINT PINK (-7890 5250);
DISPLAY INVISIBLE (-7890 5250);
FORCEPROP 1 LAST COMMENT_BODY TRUE
J 0
(12 -13);
DISPLAY 0.978723 (12 -13);
PAINT GREEN (12 -13);
DISPLAY INVISIBLE (12 -13);
FORCEPROP 2 LAST CDS_XR_PAGE_TITLE CR-56 : @T6G_MB_LIB.T6G(SCH_1):PAGE56
J 0
(-7890 5250);
DISPLAY 0.638298 (-7890 5250);
PAINT PINK (-7890 5250);
DISPLAY INVISIBLE (-7890 5250);
WIRE 16 -1 (-7575 5500)(-6900 5500);
FORCEPROP 2 LAST SIG_NAME SPI_CPU1_CLK
J 0
(-7460 5510);
DISPLAY 0.489362 (-7460 5510);
WIRE 16 -1 (-6700 5500)(-5775 5500);
FORCEPROP 2 LAST SIG_NAME SPI_CPU1_R_CLK
J 0
(-6535 5510);
DISPLAY 0.489362 (-6535 5510);
FORCEPROP 2 LASTPROP $XRERR UNIQUE?
J 0
(-6775 5510);
DISPLAY 0.638298 (-6775 5510);
PAINT MONO (-6775 5510);
DISPLAY INVISIBLE (-6775 5510);
WIRE 16 -1 (-7575 4250)(-5775 4250);
FORCEPROP 2 LAST SIG_NAME PD_ESPI_CPU1_CLK2
J 0
(-7410 4260);
DISPLAY 0.489362 (-7410 4260);
WIRE 16 -1 (-3275 3950)(-2075 3950);
FORCEPROP 2 LAST SIG_NAME NC_CPU1_USB3_USB11_TXN
J 0
(-2985 3960);
DISPLAY 0.489362 (-2985 3960);
FORCEPROP 2 LASTPROP $XRERR UNIQUE?
J 0
(-2045 3950);
DISPLAY 0.638298 (-2045 3950);
PAINT MONO (-2045 3950);
DISPLAY INVISIBLE (-2045 3950);
WIRE 16 -1 (-3275 4000)(-2075 4000);
FORCEPROP 2 LAST SIG_NAME NC_CPU1_USB3_USB11_TXP
J 0
(-2985 4010);
DISPLAY 0.489362 (-2985 4010);
FORCEPROP 2 LASTPROP $XRERR UNIQUE?
J 0
(-2045 4000);
DISPLAY 0.638298 (-2045 4000);
PAINT MONO (-2045 4000);
DISPLAY INVISIBLE (-2045 4000);
WIRE 16 -1 (-3275 3700)(-2075 3700);
FORCEPROP 2 LAST SIG_NAME NC_CPU1_USB10_OC_N
J 0
(-2985 3710);
DISPLAY 0.489362 (-2985 3710);
FORCEPROP 2 LASTPROP $XRERR UNIQUE?
J 0
(-2045 3700);
DISPLAY 0.638298 (-2045 3700);
PAINT MONO (-2045 3700);
DISPLAY INVISIBLE (-2045 3700);
WIRE 16 -1 (-3275 3650)(-2075 3650);
FORCEPROP 2 LAST SIG_NAME NC_CPU1_USB11_OC_N
J 0
(-2985 3660);
DISPLAY 0.489362 (-2985 3660);
FORCEPROP 2 LASTPROP $XRERR UNIQUE?
J 0
(-2045 3650);
DISPLAY 0.638298 (-2045 3650);
PAINT MONO (-2045 3650);
DISPLAY INVISIBLE (-2045 3650);
WIRE 16 -1 (-3275 3800)(-2075 3800);
FORCEPROP 2 LAST SIG_NAME NC_CPU1_USB00_OC_N
J 0
(-2985 3810);
DISPLAY 0.489362 (-2985 3810);
FORCEPROP 2 LASTPROP $XRERR UNIQUE?
J 0
(-2045 3800);
DISPLAY 0.638298 (-2045 3800);
PAINT MONO (-2045 3800);
DISPLAY INVISIBLE (-2045 3800);
WIRE 16 -1 (-3275 3750)(-2075 3750);
FORCEPROP 2 LAST SIG_NAME NC_CPU1_USB01_OC_N
J 0
(-2985 3760);
DISPLAY 0.489362 (-2985 3760);
FORCEPROP 2 LASTPROP $XRERR UNIQUE?
J 0
(-2045 3750);
DISPLAY 0.638298 (-2045 3750);
PAINT MONO (-2045 3750);
DISPLAY INVISIBLE (-2045 3750);
WIRE 16 -1 (-3275 5700)(-2075 5700);
FORCEPROP 2 LAST SIG_NAME NC_CPU1_USB2_USB00_DN
J 0
(-2985 5710);
DISPLAY 0.489362 (-2985 5710);
FORCEPROP 2 LASTPROP $XRERR UNIQUE?
J 0
(-2045 5700);
DISPLAY 0.638298 (-2045 5700);
PAINT MONO (-2045 5700);
DISPLAY INVISIBLE (-2045 5700);
WIRE 16 -1 (-3275 5750)(-2075 5750);
FORCEPROP 2 LAST SIG_NAME NC_CPU1_USB2_USB00_DP
J 0
(-2985 5760);
DISPLAY 0.489362 (-2985 5760);
FORCEPROP 2 LASTPROP $XRERR UNIQUE?
J 0
(-2045 5750);
DISPLAY 0.638298 (-2045 5750);
PAINT MONO (-2045 5750);
DISPLAY INVISIBLE (-2045 5750);
WIRE 16 -1 (-3275 5050)(-2075 5050);
FORCEPROP 2 LAST SIG_NAME NC_CPU1_USB3_USB00_RXN
J 0
(-2985 5060);
DISPLAY 0.489362 (-2985 5060);
FORCEPROP 2 LASTPROP $XRERR UNIQUE?
J 0
(-2045 5050);
DISPLAY 0.638298 (-2045 5050);
PAINT MONO (-2045 5050);
DISPLAY INVISIBLE (-2045 5050);
WIRE 16 -1 (-3275 5100)(-2075 5100);
FORCEPROP 2 LAST SIG_NAME NC_CPU1_USB3_USB00_RXP
J 0
(-2985 5110);
DISPLAY 0.489362 (-2985 5110);
FORCEPROP 2 LASTPROP $XRERR UNIQUE?
J 0
(-2045 5100);
DISPLAY 0.638298 (-2045 5100);
PAINT MONO (-2045 5100);
DISPLAY INVISIBLE (-2045 5100);
WIRE 16 -1 (-3275 4400)(-2075 4400);
FORCEPROP 2 LAST SIG_NAME NC_CPU1_USB3_USB00_TXP
J 0
(-2985 4410);
DISPLAY 0.489362 (-2985 4410);
FORCEPROP 2 LASTPROP $XRERR UNIQUE?
J 0
(-2045 4400);
DISPLAY 0.638298 (-2045 4400);
PAINT MONO (-2045 4400);
DISPLAY INVISIBLE (-2045 4400);
WIRE 16 -1 (-3275 4450)(-2075 4450);
FORCEPROP 2 LAST SIG_NAME NC_CPU1_USB3_USB00_TXN
J 0
(-2985 4460);
DISPLAY 0.489362 (-2985 4460);
FORCEPROP 2 LASTPROP $XRERR UNIQUE?
J 0
(-2045 4450);
DISPLAY 0.638298 (-2045 4450);
PAINT MONO (-2045 4450);
DISPLAY INVISIBLE (-2045 4450);
WIRE 16 -1 (-3275 5550)(-2075 5550);
FORCEPROP 2 LAST SIG_NAME NC_CPU1_USB2_USB01_DN
J 0
(-2985 5560);
DISPLAY 0.489362 (-2985 5560);
FORCEPROP 2 LASTPROP $XRERR UNIQUE?
J 0
(-2045 5550);
DISPLAY 0.638298 (-2045 5550);
PAINT MONO (-2045 5550);
DISPLAY INVISIBLE (-2045 5550);
WIRE 16 -1 (-3275 5600)(-2075 5600);
FORCEPROP 2 LAST SIG_NAME NC_CPU1_USB2_USB01_DP
J 0
(-2985 5610);
DISPLAY 0.489362 (-2985 5610);
FORCEPROP 2 LASTPROP $XRERR UNIQUE?
J 0
(-2045 5600);
DISPLAY 0.638298 (-2045 5600);
PAINT MONO (-2045 5600);
DISPLAY INVISIBLE (-2045 5600);
WIRE 16 -1 (-3275 4900)(-2075 4900);
FORCEPROP 2 LAST SIG_NAME NC_CPU1_USB3_USB01_RXN
J 0
(-2985 4910);
DISPLAY 0.489362 (-2985 4910);
FORCEPROP 2 LASTPROP $XRERR UNIQUE?
J 0
(-2045 4900);
DISPLAY 0.638298 (-2045 4900);
PAINT MONO (-2045 4900);
DISPLAY INVISIBLE (-2045 4900);
WIRE 16 -1 (-3275 4950)(-2075 4950);
FORCEPROP 2 LAST SIG_NAME NC_CPU1_USB3_USB01_RXP
J 0
(-2985 4960);
DISPLAY 0.489362 (-2985 4960);
FORCEPROP 2 LASTPROP $XRERR UNIQUE?
J 0
(-2045 4950);
DISPLAY 0.638298 (-2045 4950);
PAINT MONO (-2045 4950);
DISPLAY INVISIBLE (-2045 4950);
WIRE 16 -1 (-3275 4250)(-2075 4250);
FORCEPROP 2 LAST SIG_NAME NC_CPU1_USB3_USB01_TXN
J 0
(-2985 4260);
DISPLAY 0.489362 (-2985 4260);
FORCEPROP 2 LASTPROP $XRERR UNIQUE?
J 0
(-2045 4250);
DISPLAY 0.638298 (-2045 4250);
PAINT MONO (-2045 4250);
DISPLAY INVISIBLE (-2045 4250);
WIRE 16 -1 (-3275 4300)(-2075 4300);
FORCEPROP 2 LAST SIG_NAME NC_CPU1_USB3_USB01_TXP
J 0
(-2985 4310);
DISPLAY 0.489362 (-2985 4310);
FORCEPROP 2 LASTPROP $XRERR UNIQUE?
J 0
(-2045 4300);
DISPLAY 0.638298 (-2045 4300);
PAINT MONO (-2045 4300);
DISPLAY INVISIBLE (-2045 4300);
WIRE 16 -1 (-3275 5400)(-2075 5400);
FORCEPROP 2 LAST SIG_NAME NC_CPU1_USB2_USB10_DN
J 0
(-2985 5410);
DISPLAY 0.489362 (-2985 5410);
FORCEPROP 2 LASTPROP $XRERR UNIQUE?
J 0
(-2045 5400);
DISPLAY 0.638298 (-2045 5400);
PAINT MONO (-2045 5400);
DISPLAY INVISIBLE (-2045 5400);
WIRE 16 -1 (-3275 5450)(-2075 5450);
FORCEPROP 2 LAST SIG_NAME NC_CPU1_USB2_USB10_DP
J 0
(-2985 5460);
DISPLAY 0.489362 (-2985 5460);
FORCEPROP 2 LASTPROP $XRERR UNIQUE?
J 0
(-2045 5450);
DISPLAY 0.638298 (-2045 5450);
PAINT MONO (-2045 5450);
DISPLAY INVISIBLE (-2045 5450);
WIRE 16 -1 (-3275 4750)(-2075 4750);
FORCEPROP 2 LAST SIG_NAME NC_CPU1_USB3_USB10_RXN
J 0
(-2985 4760);
DISPLAY 0.489362 (-2985 4760);
FORCEPROP 2 LASTPROP $XRERR UNIQUE?
J 0
(-2045 4750);
DISPLAY 0.638298 (-2045 4750);
PAINT MONO (-2045 4750);
DISPLAY INVISIBLE (-2045 4750);
WIRE 16 -1 (-3275 4800)(-2075 4800);
FORCEPROP 2 LAST SIG_NAME NC_CPU1_USB3_USB10_RXP
J 0
(-2985 4810);
DISPLAY 0.489362 (-2985 4810);
FORCEPROP 2 LASTPROP $XRERR UNIQUE?
J 0
(-2045 4800);
DISPLAY 0.638298 (-2045 4800);
PAINT MONO (-2045 4800);
DISPLAY INVISIBLE (-2045 4800);
WIRE 16 -1 (-3275 4100)(-2075 4100);
FORCEPROP 2 LAST SIG_NAME NC_CPU1_USB3_USB10_TXN
J 0
(-2985 4110);
DISPLAY 0.489362 (-2985 4110);
FORCEPROP 2 LASTPROP $XRERR UNIQUE?
J 0
(-2045 4100);
DISPLAY 0.638298 (-2045 4100);
PAINT MONO (-2045 4100);
DISPLAY INVISIBLE (-2045 4100);
WIRE 16 -1 (-3275 4150)(-2075 4150);
FORCEPROP 2 LAST SIG_NAME NC_CPU1_USB3_USB10_TXP
J 0
(-2985 4160);
DISPLAY 0.489362 (-2985 4160);
FORCEPROP 2 LASTPROP $XRERR UNIQUE?
J 0
(-2045 4150);
DISPLAY 0.638298 (-2045 4150);
PAINT MONO (-2045 4150);
DISPLAY INVISIBLE (-2045 4150);
WIRE 16 -1 (-3275 5250)(-2075 5250);
FORCEPROP 2 LAST SIG_NAME NC_CPU1_USB2_USB11_DN
J 0
(-2985 5260);
DISPLAY 0.489362 (-2985 5260);
FORCEPROP 2 LASTPROP $XRERR UNIQUE?
J 0
(-2045 5250);
DISPLAY 0.638298 (-2045 5250);
PAINT MONO (-2045 5250);
DISPLAY INVISIBLE (-2045 5250);
WIRE 16 -1 (-3275 5300)(-2075 5300);
FORCEPROP 2 LAST SIG_NAME NC_CPU1_USB2_USB11_DP
J 0
(-2985 5310);
DISPLAY 0.489362 (-2985 5310);
FORCEPROP 2 LASTPROP $XRERR UNIQUE?
J 0
(-2045 5300);
DISPLAY 0.638298 (-2045 5300);
PAINT MONO (-2045 5300);
DISPLAY INVISIBLE (-2045 5300);
WIRE 16 -1 (-3275 4600)(-2075 4600);
FORCEPROP 2 LAST SIG_NAME NC_CPU1_USB3_USB11_RXN
J 0
(-2985 4610);
DISPLAY 0.489362 (-2985 4610);
FORCEPROP 2 LASTPROP $XRERR UNIQUE?
J 0
(-2045 4600);
DISPLAY 0.638298 (-2045 4600);
PAINT MONO (-2045 4600);
DISPLAY INVISIBLE (-2045 4600);
WIRE 16 -1 (-3275 4650)(-2075 4650);
FORCEPROP 2 LAST SIG_NAME NC_CPU1_USB3_USB11_RXP
J 0
(-2985 4660);
DISPLAY 0.489362 (-2985 4660);
FORCEPROP 2 LASTPROP $XRERR UNIQUE?
J 0
(-2045 4650);
DISPLAY 0.638298 (-2045 4650);
PAINT MONO (-2045 4650);
DISPLAY INVISIBLE (-2045 4650);
QUIT
